FILE_TYPE = MULTI_PHYS_TABLE;

PART 'ICP_10100_LGA10'
CLASS = IC 

{========================================================================================}
:CLS_PN           | VALUE         = JEDEC_TYPE         | ALT_SYMBOLS         | DESCRIPTION                                                           | CPN_STATUS ;
{========================================================================================}
 'A222-00002-FB'  |'ICP-10100'    = 'LGA10_079_P0197'  |'(LGA10_079_P0197)'  |'IC,ICP-10100,BAROMETRIC PRESSURE AND TEMPERATURE SENSOR,SMT,LGA-10L'  | '' 

END_PART

END.

